(kicad_pcb
	(version 20260206)
	(generator "pcbnew")
	(generator_version "10.0")
	(general
		(thickness 1.6)
		(legacy_teardrops no)
	)
	(paper "A4")
	(title_block
		(title "03242023_DA0F0TMBIJ0_F0T_Motherboard_J_brd_V01_OCP.brd")
		(comment 1 "Grand Teton / footprints 5993-5998 of 6105")
	)
	(layers
		(0 "F.Cu" signal "TOP")
		(4 "In1.Cu" signal "GND")
		(6 "In2.Cu" signal "IN1")
		(8 "In3.Cu" signal "GND1")
		(10 "In4.Cu" signal "IN2")
		(12 "In5.Cu" signal "GND2")
		(14 "In6.Cu" signal "IN3")
		(16 "In7.Cu" signal "GND3")
		(18 "In8.Cu" signal "VCC")
		(20 "In9.Cu" signal "VCC1")
		(22 "In10.Cu" signal "GND4")
		(24 "In11.Cu" signal "IN4")
		(26 "In12.Cu" signal "GND5")
		(28 "In13.Cu" signal "IN5")
		(30 "In14.Cu" signal "GND6")
		(32 "In15.Cu" signal "IN6")
		(34 "In16.Cu" signal "GND7")
		(2 "B.Cu" signal "BOTTOM")
		(9 "F.Adhes" user "F.Adhesive")
		(11 "B.Adhes" user "B.Adhesive")
		(13 "F.Paste" user "Package Geometry/Pastemask Top")
		(15 "B.Paste" user "Package Geometry/Pastemask Bottom")
		(5 "F.SilkS" user "Ref Des/Silkscreen Top")
		(7 "B.SilkS" user "Ref Des/Silkscreen Bottom")
		(1 "F.Mask" user "Board Geometry/Soldermask Top")
		(3 "B.Mask" user "Board Geometry/Soldermask Bottom")
		(17 "Dwgs.User" user "User.Drawings")
		(19 "Cmts.User" user "User.Comments")
		(21 "Eco1.User" user "User.Eco1")
		(23 "Eco2.User" user "User.Eco2")
		(25 "Edge.Cuts" user "Board Geometry/Outline")
		(27 "Margin" user)
		(31 "F.CrtYd" user "Package Geometry/Place Bound Top")
		(29 "B.CrtYd" user "Package Geometry/Place Bound Bottom")
		(35 "F.Fab" user "Ref Des/Assembly Top")
		(33 "B.Fab" user "Ref Des/Assembly Bottom")
	)
	(footprint ""
		(layer "B.Cu")
		(at 234.894628 -123.015248 90)
		(property "Reference" "C209"
			(at 0 0 90)
			(layer "B.SilkS")
			(hide yes)
			(effects
				(font
					(size 1.27 1.27)
				)
				(justify mirror)
			)
		)
		(property "Value" ""
			(at 0 0 90)
			(layer "B.Fab")
			(effects
				(font
					(size 1.27 1.27)
				)
				(justify mirror)
			)
		)
		(duplicate_pad_numbers_are_jumpers no)
		(fp_line
			(start 1.2954 -0.5842)
			(end -1.2954 -0.5842)
			(stroke
				(width 0.1524)
				(type default)
			)
			(layer "B.SilkS")
		)
		(fp_line
			(start 0 -0.5842)
			(end 0 0.5842)
			(stroke
				(width 0.1524)
				(type default)
			)
			(layer "B.SilkS")
		)
		(fp_line
			(start -1.2954 -0.5842)
			(end -1.2954 0.5842)
			(stroke
				(width 0.1524)
				(type default)
			)
			(layer "B.SilkS")
		)
		(fp_line
			(start 1.2954 0.5842)
			(end 1.2954 -0.5842)
			(stroke
				(width 0.1524)
				(type default)
			)
			(layer "B.SilkS")
		)
		(fp_line
			(start -1.2954 0.5842)
			(end 1.2954 0.5842)
			(stroke
				(width 0.1524)
				(type default)
			)
			(layer "B.SilkS")
		)
		(fp_line
			(start 0.8636 -0.4572)
			(end -0.8636 -0.4572)
			(stroke
				(width 0.1)
				(type default)
			)
			(layer "B.Fab")
		)
		(fp_line
			(start -0.8636 -0.4572)
			(end -0.8636 -0.4064)
			(stroke
				(width 0.1)
				(type default)
			)
			(layer "B.Fab")
		)
		(fp_line
			(start 1.1938 -0.4064)
			(end 0.8636 -0.4064)
			(stroke
				(width 0.1)
				(type default)
			)
			(layer "B.Fab")
		)
		(fp_line
			(start 0.8636 -0.4064)
			(end 0.8636 -0.4572)
			(stroke
				(width 0.1)
				(type default)
			)
			(layer "B.Fab")
		)
		(fp_line
			(start -0.8636 -0.4064)
			(end -1.1938 -0.4064)
			(stroke
				(width 0.1)
				(type default)
			)
			(layer "B.Fab")
		)
		(fp_line
			(start -1.1938 -0.4064)
			(end -1.1938 0.4064)
			(stroke
				(width 0.1)
				(type default)
			)
			(layer "B.Fab")
		)
		(fp_line
			(start 1.1938 0.4064)
			(end 1.1938 -0.4064)
			(stroke
				(width 0.1)
				(type default)
			)
			(layer "B.Fab")
		)
		(fp_line
			(start 0.8636 0.4064)
			(end 1.1938 0.4064)
			(stroke
				(width 0.1)
				(type default)
			)
			(layer "B.Fab")
		)
		(fp_line
			(start -0.8636 0.4064)
			(end -0.8636 0.4572)
			(stroke
				(width 0.1)
				(type default)
			)
			(layer "B.Fab")
		)
		(fp_line
			(start -1.1938 0.4064)
			(end -0.8636 0.4064)
			(stroke
				(width 0.1)
				(type default)
			)
			(layer "B.Fab")
		)
		(fp_line
			(start 0.8636 0.4572)
			(end 0.8636 0.4064)
			(stroke
				(width 0.1)
				(type default)
			)
			(layer "B.Fab")
		)
		(fp_line
			(start -0.8636 0.4572)
			(end 0.8636 0.4572)
			(stroke
				(width 0.1)
				(type default)
			)
			(layer "B.Fab")
		)
		(pad "1" smd rect
			(at 0.7366 0)
			(size 0.7112 0.8128)
			(layers "B.Cu" "B.Mask" "B.Paste")
			(net "P3V3_DB2000_VDDA")
		)
		(pad "2" smd rect
			(at -0.7366 0)
			(size 0.7112 0.8128)
			(layers "B.Cu" "B.Mask" "B.Paste")
			(net "GND")
		)
	)
	(footprint ""
		(layer "B.Cu")
		(at 433.073302 -318.868806 90)
		(property "Reference" "R2732"
			(at 0 0 90)
			(layer "B.SilkS")
			(hide yes)
			(effects
				(font
					(size 1.27 1.27)
				)
				(justify mirror)
			)
		)
		(property "Value" ""
			(at 0 0 90)
			(layer "B.Fab")
			(effects
				(font
					(size 1.27 1.27)
				)
				(justify mirror)
			)
		)
		(duplicate_pad_numbers_are_jumpers no)
		(fp_line
			(start 0.7874 -0.4064)
			(end -0.7874 -0.4064)
			(stroke
				(width 0.1524)
				(type default)
			)
			(layer "B.SilkS")
		)
		(fp_line
			(start -0.7874 -0.4064)
			(end -0.7874 0.4064)
			(stroke
				(width 0.1524)
				(type default)
			)
			(layer "B.SilkS")
		)
		(fp_line
			(start 0.7874 0.4064)
			(end 0.7874 -0.4064)
			(stroke
				(width 0.1524)
				(type default)
			)
			(layer "B.SilkS")
		)
		(fp_line
			(start -0.7874 0.4064)
			(end 0.7874 0.4064)
			(stroke
				(width 0.1524)
				(type default)
			)
			(layer "B.SilkS")
		)
		(fp_line
			(start 0.67945 -0.305054)
			(end 0.12065 -0.305054)
			(stroke
				(width 0.1)
				(type default)
			)
			(layer "B.Fab")
		)
		(fp_line
			(start 0.12065 -0.305054)
			(end 0.12065 -0.2794)
			(stroke
				(width 0.1)
				(type default)
			)
			(layer "B.Fab")
		)
		(fp_line
			(start -0.12065 -0.3048)
			(end -0.67945 -0.3048)
			(stroke
				(width 0.1)
				(type default)
			)
			(layer "B.Fab")
		)
		(fp_line
			(start -0.67945 -0.3048)
			(end -0.67945 0.3048)
			(stroke
				(width 0.1)
				(type default)
			)
			(layer "B.Fab")
		)
		(fp_line
			(start 0.12065 -0.2794)
			(end -0.12065 -0.2794)
			(stroke
				(width 0.1)
				(type default)
			)
			(layer "B.Fab")
		)
		(fp_line
			(start -0.12065 -0.2794)
			(end -0.12065 -0.3048)
			(stroke
				(width 0.1)
				(type default)
			)
			(layer "B.Fab")
		)
		(fp_line
			(start 0.12065 0.2794)
			(end 0.12065 0.3048)
			(stroke
				(width 0.1)
				(type default)
			)
			(layer "B.Fab")
		)
		(fp_line
			(start -0.120396 0.2794)
			(end 0.12065 0.2794)
			(stroke
				(width 0.1)
				(type default)
			)
			(layer "B.Fab")
		)
		(fp_line
			(start 0.67945 0.3048)
			(end 0.67945 -0.305054)
			(stroke
				(width 0.1)
				(type default)
			)
			(layer "B.Fab")
		)
		(fp_line
			(start 0.12065 0.3048)
			(end 0.67945 0.3048)
			(stroke
				(width 0.1)
				(type default)
			)
			(layer "B.Fab")
		)
		(fp_line
			(start -0.120396 0.3048)
			(end -0.120396 0.2794)
			(stroke
				(width 0.1)
				(type default)
			)
			(layer "B.Fab")
		)
		(fp_line
			(start -0.67945 0.3048)
			(end -0.120396 0.3048)
			(stroke
				(width 0.1)
				(type default)
			)
			(layer "B.Fab")
		)
		(pad "1" smd circle
			(at 0.40005 0 270)
			(size 0 0)
			(layers "B.Cu" "B.Mask" "B.Paste")
			(net "PWRGD_CHF_CPU0_DIMM1")
		)
		(pad "2" smd circle
			(at -0.40005 0 270)
			(size 0 0)
			(layers "B.Cu" "B.Mask" "B.Paste")
			(net "PWRGD_FAIL_CPU0_EF")
		)
	)
	(footprint ""
		(layer "B.Cu")
		(at 430.77384 -122.281188 180)
		(property "Reference" "PR369"
			(at 0 0 0)
			(layer "B.SilkS")
			(hide yes)
			(effects
				(font
					(size 1.27 1.27)
				)
				(justify mirror)
			)
		)
		(property "Value" ""
			(at 0 0 0)
			(layer "B.Fab")
			(effects
				(font
					(size 1.27 1.27)
				)
				(justify mirror)
			)
		)
		(duplicate_pad_numbers_are_jumpers no)
		(fp_line
			(start 0.7874 0.4064)
			(end 0.7874 -0.4064)
			(stroke
				(width 0.1524)
				(type default)
			)
			(layer "B.SilkS")
		)
		(fp_line
			(start 0.7874 -0.4064)
			(end -0.7874 -0.4064)
			(stroke
				(width 0.1524)
				(type default)
			)
			(layer "B.SilkS")
		)
		(fp_line
			(start -0.7874 0.4064)
			(end 0.7874 0.4064)
			(stroke
				(width 0.1524)
				(type default)
			)
			(layer "B.SilkS")
		)
		(fp_line
			(start -0.7874 -0.4064)
			(end -0.7874 0.4064)
			(stroke
				(width 0.1524)
				(type default)
			)
			(layer "B.SilkS")
		)
		(fp_line
			(start 0.67945 0.3048)
			(end 0.67945 -0.305054)
			(stroke
				(width 0.1)
				(type default)
			)
			(layer "B.Fab")
		)
		(fp_line
			(start 0.67945 -0.305054)
			(end 0.12065 -0.305054)
			(stroke
				(width 0.1)
				(type default)
			)
			(layer "B.Fab")
		)
		(fp_line
			(start 0.12065 0.3048)
			(end 0.67945 0.3048)
			(stroke
				(width 0.1)
				(type default)
			)
			(layer "B.Fab")
		)
		(fp_line
			(start 0.12065 0.2794)
			(end 0.12065 0.3048)
			(stroke
				(width 0.1)
				(type default)
			)
			(layer "B.Fab")
		)
		(fp_line
			(start 0.12065 -0.2794)
			(end -0.12065 -0.2794)
			(stroke
				(width 0.1)
				(type default)
			)
			(layer "B.Fab")
		)
		(fp_line
			(start 0.12065 -0.305054)
			(end 0.12065 -0.2794)
			(stroke
				(width 0.1)
				(type default)
			)
			(layer "B.Fab")
		)
		(fp_line
			(start -0.120396 0.3048)
			(end -0.120396 0.2794)
			(stroke
				(width 0.1)
				(type default)
			)
			(layer "B.Fab")
		)
		(fp_line
			(start -0.120396 0.2794)
			(end 0.12065 0.2794)
			(stroke
				(width 0.1)
				(type default)
			)
			(layer "B.Fab")
		)
		(fp_line
			(start -0.12065 -0.2794)
			(end -0.12065 -0.3048)
			(stroke
				(width 0.1)
				(type default)
			)
			(layer "B.Fab")
		)
		(fp_line
			(start -0.12065 -0.3048)
			(end -0.67945 -0.3048)
			(stroke
				(width 0.1)
				(type default)
			)
			(layer "B.Fab")
		)
		(fp_line
			(start -0.67945 0.3048)
			(end -0.120396 0.3048)
			(stroke
				(width 0.1)
				(type default)
			)
			(layer "B.Fab")
		)
		(fp_line
			(start -0.67945 -0.3048)
			(end -0.67945 0.3048)
			(stroke
				(width 0.1)
				(type default)
			)
			(layer "B.Fab")
		)
		(pad "1" smd circle
			(at 0.40005 0)
			(size 0 0)
			(layers "B.Cu" "B.Mask" "B.Paste")
			(net "PVCCD_HV_CPU0_ISENSE_P")
		)
		(pad "2" smd circle
			(at -0.40005 0)
			(size 0 0)
			(layers "B.Cu" "B.Mask" "B.Paste")
			(net "GND")
		)
	)
	(footprint ""
		(layer "B.Cu")
		(at 150.42388 -22.824948 -90)
		(property "Reference" "R2213"
			(at 0 0 90)
			(layer "B.SilkS")
			(hide yes)
			(effects
				(font
					(size 1.27 1.27)
				)
				(justify mirror)
			)
		)
		(property "Value" ""
			(at 0 0 90)
			(layer "B.Fab")
			(effects
				(font
					(size 1.27 1.27)
				)
				(justify mirror)
			)
		)
		(duplicate_pad_numbers_are_jumpers no)
		(fp_line
			(start -0.7874 0.4064)
			(end 0.7874 0.4064)
			(stroke
				(width 0.1524)
				(type default)
			)
			(layer "B.SilkS")
		)
		(fp_line
			(start 0.7874 0.4064)
			(end 0.7874 -0.4064)
			(stroke
				(width 0.1524)
				(type default)
			)
			(layer "B.SilkS")
		)
		(fp_line
			(start -0.7874 -0.4064)
			(end -0.7874 0.4064)
			(stroke
				(width 0.1524)
				(type default)
			)
			(layer "B.SilkS")
		)
		(fp_line
			(start 0.7874 -0.4064)
			(end -0.7874 -0.4064)
			(stroke
				(width 0.1524)
				(type default)
			)
			(layer "B.SilkS")
		)
		(fp_line
			(start -0.67945 0.3048)
			(end -0.120396 0.3048)
			(stroke
				(width 0.1)
				(type default)
			)
			(layer "B.Fab")
		)
		(fp_line
			(start -0.120396 0.3048)
			(end -0.120396 0.2794)
			(stroke
				(width 0.1)
				(type default)
			)
			(layer "B.Fab")
		)
		(fp_line
			(start 0.12065 0.3048)
			(end 0.67945 0.3048)
			(stroke
				(width 0.1)
				(type default)
			)
			(layer "B.Fab")
		)
		(fp_line
			(start 0.67945 0.3048)
			(end 0.67945 -0.305054)
			(stroke
				(width 0.1)
				(type default)
			)
			(layer "B.Fab")
		)
		(fp_line
			(start -0.120396 0.2794)
			(end 0.12065 0.2794)
			(stroke
				(width 0.1)
				(type default)
			)
			(layer "B.Fab")
		)
		(fp_line
			(start 0.12065 0.2794)
			(end 0.12065 0.3048)
			(stroke
				(width 0.1)
				(type default)
			)
			(layer "B.Fab")
		)
		(fp_line
			(start -0.12065 -0.2794)
			(end -0.12065 -0.3048)
			(stroke
				(width 0.1)
				(type default)
			)
			(layer "B.Fab")
		)
		(fp_line
			(start 0.12065 -0.2794)
			(end -0.12065 -0.2794)
			(stroke
				(width 0.1)
				(type default)
			)
			(layer "B.Fab")
		)
		(fp_line
			(start -0.67945 -0.3048)
			(end -0.67945 0.3048)
			(stroke
				(width 0.1)
				(type default)
			)
			(layer "B.Fab")
		)
		(fp_line
			(start -0.12065 -0.3048)
			(end -0.67945 -0.3048)
			(stroke
				(width 0.1)
				(type default)
			)
			(layer "B.Fab")
		)
		(fp_line
			(start 0.12065 -0.305054)
			(end 0.12065 -0.2794)
			(stroke
				(width 0.1)
				(type default)
			)
			(layer "B.Fab")
		)
		(fp_line
			(start 0.67945 -0.305054)
			(end 0.12065 -0.305054)
			(stroke
				(width 0.1)
				(type default)
			)
			(layer "B.Fab")
		)
		(pad "1" smd circle
			(at 0.40005 0 90)
			(size 0 0)
			(layers "B.Cu" "B.Mask" "B.Paste")
			(net "SMB_S3M_CPU_3V3AUX_SDA")
		)
		(pad "2" smd circle
			(at -0.40005 0 90)
			(size 0 0)
			(layers "B.Cu" "B.Mask" "B.Paste")
			(net "P3V3_AUX")
		)
	)
	(footprint ""
		(layer "B.Cu")
		(at 270.700246 -193.503296 -90)
		(property "Reference" "R841"
			(at 0 0 90)
			(layer "B.SilkS")
			(hide yes)
			(effects
				(font
					(size 1.27 1.27)
				)
				(justify mirror)
			)
		)
		(property "Value" ""
			(at 0 0 90)
			(layer "B.Fab")
			(effects
				(font
					(size 1.27 1.27)
				)
				(justify mirror)
			)
		)
		(duplicate_pad_numbers_are_jumpers no)
		(fp_line
			(start -0.7874 0.4064)
			(end 0.7874 0.4064)
			(stroke
				(width 0.1524)
				(type default)
			)
			(layer "B.SilkS")
		)
		(fp_line
			(start 0.7874 0.4064)
			(end 0.7874 -0.4064)
			(stroke
				(width 0.1524)
				(type default)
			)
			(layer "B.SilkS")
		)
		(fp_line
			(start -0.7874 -0.4064)
			(end -0.7874 0.4064)
			(stroke
				(width 0.1524)
				(type default)
			)
			(layer "B.SilkS")
		)
		(fp_line
			(start 0.7874 -0.4064)
			(end -0.7874 -0.4064)
			(stroke
				(width 0.1524)
				(type default)
			)
			(layer "B.SilkS")
		)
		(fp_line
			(start -0.67945 0.3048)
			(end -0.120396 0.3048)
			(stroke
				(width 0.1)
				(type default)
			)
			(layer "B.Fab")
		)
		(fp_line
			(start -0.120396 0.3048)
			(end -0.120396 0.2794)
			(stroke
				(width 0.1)
				(type default)
			)
			(layer "B.Fab")
		)
		(fp_line
			(start 0.12065 0.3048)
			(end 0.67945 0.3048)
			(stroke
				(width 0.1)
				(type default)
			)
			(layer "B.Fab")
		)
		(fp_line
			(start 0.67945 0.3048)
			(end 0.67945 -0.305054)
			(stroke
				(width 0.1)
				(type default)
			)
			(layer "B.Fab")
		)
		(fp_line
			(start -0.120396 0.2794)
			(end 0.12065 0.2794)
			(stroke
				(width 0.1)
				(type default)
			)
			(layer "B.Fab")
		)
		(fp_line
			(start 0.12065 0.2794)
			(end 0.12065 0.3048)
			(stroke
				(width 0.1)
				(type default)
			)
			(layer "B.Fab")
		)
		(fp_line
			(start -0.12065 -0.2794)
			(end -0.12065 -0.3048)
			(stroke
				(width 0.1)
				(type default)
			)
			(layer "B.Fab")
		)
		(fp_line
			(start 0.12065 -0.2794)
			(end -0.12065 -0.2794)
			(stroke
				(width 0.1)
				(type default)
			)
			(layer "B.Fab")
		)
		(fp_line
			(start -0.67945 -0.3048)
			(end -0.67945 0.3048)
			(stroke
				(width 0.1)
				(type default)
			)
			(layer "B.Fab")
		)
		(fp_line
			(start -0.12065 -0.3048)
			(end -0.67945 -0.3048)
			(stroke
				(width 0.1)
				(type default)
			)
			(layer "B.Fab")
		)
		(fp_line
			(start 0.12065 -0.305054)
			(end 0.12065 -0.2794)
			(stroke
				(width 0.1)
				(type default)
			)
			(layer "B.Fab")
		)
		(fp_line
			(start 0.67945 -0.305054)
			(end 0.12065 -0.305054)
			(stroke
				(width 0.1)
				(type default)
			)
			(layer "B.Fab")
		)
		(pad "1" smd circle
			(at 0.40005 0 90)
			(size 0 0)
			(layers "B.Cu" "B.Mask" "B.Paste")
			(net "PVCCD_HV_CPU0")
		)
		(pad "2" smd circle
			(at -0.40005 0 90)
			(size 0 0)
			(layers "B.Cu" "B.Mask" "B.Paste")
			(net "RST_M_CD_CPU0_FPGA_N")
		)
	)
	(footprint ""
		(layer "B.Cu")
		(at 27.375866 -193.152776 -90)
		(property "Reference" "R821"
			(at 0 0 90)
			(layer "B.SilkS")
			(hide yes)
			(effects
				(font
					(size 1.27 1.27)
				)
				(justify mirror)
			)
		)
		(property "Value" ""
			(at 0 0 90)
			(layer "B.Fab")
			(effects
				(font
					(size 1.27 1.27)
				)
				(justify mirror)
			)
		)
		(duplicate_pad_numbers_are_jumpers no)
		(fp_line
			(start -0.7874 0.4064)
			(end 0.7874 0.4064)
			(stroke
				(width 0.1524)
				(type default)
			)
			(layer "B.SilkS")
		)
		(fp_line
			(start 0.7874 0.4064)
			(end 0.7874 -0.4064)
			(stroke
				(width 0.1524)
				(type default)
			)
			(layer "B.SilkS")
		)
		(fp_line
			(start -0.7874 -0.4064)
			(end -0.7874 0.4064)
			(stroke
				(width 0.1524)
				(type default)
			)
			(layer "B.SilkS")
		)
		(fp_line
			(start 0.7874 -0.4064)
			(end -0.7874 -0.4064)
			(stroke
				(width 0.1524)
				(type default)
			)
			(layer "B.SilkS")
		)
		(fp_line
			(start -0.67945 0.3048)
			(end -0.120396 0.3048)
			(stroke
				(width 0.1)
				(type default)
			)
			(layer "B.Fab")
		)
		(fp_line
			(start -0.120396 0.3048)
			(end -0.120396 0.2794)
			(stroke
				(width 0.1)
				(type default)
			)
			(layer "B.Fab")
		)
		(fp_line
			(start 0.12065 0.3048)
			(end 0.67945 0.3048)
			(stroke
				(width 0.1)
				(type default)
			)
			(layer "B.Fab")
		)
		(fp_line
			(start 0.67945 0.3048)
			(end 0.67945 -0.305054)
			(stroke
				(width 0.1)
				(type default)
			)
			(layer "B.Fab")
		)
		(fp_line
			(start -0.120396 0.2794)
			(end 0.12065 0.2794)
			(stroke
				(width 0.1)
				(type default)
			)
			(layer "B.Fab")
		)
		(fp_line
			(start 0.12065 0.2794)
			(end 0.12065 0.3048)
			(stroke
				(width 0.1)
				(type default)
			)
			(layer "B.Fab")
		)
		(fp_line
			(start -0.12065 -0.2794)
			(end -0.12065 -0.3048)
			(stroke
				(width 0.1)
				(type default)
			)
			(layer "B.Fab")
		)
		(fp_line
			(start 0.12065 -0.2794)
			(end -0.12065 -0.2794)
			(stroke
				(width 0.1)
				(type default)
			)
			(layer "B.Fab")
		)
		(fp_line
			(start -0.67945 -0.3048)
			(end -0.67945 0.3048)
			(stroke
				(width 0.1)
				(type default)
			)
			(layer "B.Fab")
		)
		(fp_line
			(start -0.12065 -0.3048)
			(end -0.67945 -0.3048)
			(stroke
				(width 0.1)
				(type default)
			)
			(layer "B.Fab")
		)
		(fp_line
			(start 0.12065 -0.305054)
			(end 0.12065 -0.2794)
			(stroke
				(width 0.1)
				(type default)
			)
			(layer "B.Fab")
		)
		(fp_line
			(start 0.67945 -0.305054)
			(end 0.12065 -0.305054)
			(stroke
				(width 0.1)
				(type default)
			)
			(layer "B.Fab")
		)
		(pad "1" smd circle
			(at 0.40005 0 90)
			(size 0 0)
			(layers "B.Cu" "B.Mask" "B.Paste")
			(net "PVCCD_HV_CPU1")
		)
		(pad "2" smd circle
			(at -0.40005 0 90)
			(size 0 0)
			(layers "B.Cu" "B.Mask" "B.Paste")
			(net "RST_M_CD_CPU1_FPGA_N")
		)
	)
)
